# BASEBOARD_FAB2 (Tioga Pass) — schematic netlist excerpt (pin names and nets, part order shuffled) for the footprints in the layout excerpt that follows; sources: Cadence DE-HDL packaged netlist, KiCad conversion of Wiwynn_Tioga_Pass_MB.brd

CR2U1  DIODE2A_DUAL  BAS70-05 DIO  pkg SMLF  page 196
  A1  = P3V3_STBY
  A2  = A_P3V_BAT_R
  C  = P3V3_RTC_STBY

R1L21  RES  64.9 1.0% CHIP  pkg 0402  page 177 : A = P3V3 ; B = FP_LED_HDD_ACTIVITY_AND_R_N
C1M38  CAP_A  0.1UF 16V 10% X7R  pkg 0402V  page 176 : A = P5V_TPS2061 ; B = GND

(kicad_pcb
	(version 20260206)
	(generator "pcbnew")
	(generator_version "10.0")
	(general
		(thickness 1.6)
		(legacy_teardrops no)
	)
	(paper "A4")
	(title_block
		(title "Wiwynn_Tioga_Pass_MB.brd")
		(comment 1 "Tioga Pass / footprints 4370-4372 of 4770")
	)
	(layers
		(0 "F.Cu" signal "TOP")
		(4 "In1.Cu" signal "L2GND")
		(6 "In2.Cu" signal "L3")
		(8 "In3.Cu" signal "L4GND")
		(10 "In4.Cu" signal "L5")
		(12 "In5.Cu" signal "L6GND")
		(14 "In6.Cu" signal "L7VCC")
		(16 "In7.Cu" signal "L8VCC")
		(18 "In8.Cu" signal "L9GND")
		(20 "In9.Cu" signal "L10")
		(22 "In10.Cu" signal "L11GND")
		(24 "In11.Cu" signal "L12")
		(26 "In12.Cu" signal "L13GND")
		(2 "B.Cu" signal "BOTTOM")
		(9 "F.Adhes" user "F.Adhesive")
		(11 "B.Adhes" user "B.Adhesive")
		(13 "F.Paste" user "Package Geometry/Pastemask Top")
		(15 "B.Paste" user "Package Geometry/Pastemask Bottom")
		(5 "F.SilkS" user "Ref Des/Silkscreen Top")
		(7 "B.SilkS" user "Ref Des/Silkscreen Bottom")
		(1 "F.Mask" user "Board Geometry/Soldermask Top")
		(3 "B.Mask" user "Board Geometry/Soldermask Bottom")
		(17 "Dwgs.User" user "User.Drawings")
		(19 "Cmts.User" user "User.Comments")
		(21 "Eco1.User" user "User.Eco1")
		(23 "Eco2.User" user "User.Eco2")
		(25 "Edge.Cuts" user "Board Geometry/Outline")
		(27 "Margin" user)
		(31 "F.CrtYd" user "Package Geometry/Place Bound Top")
		(29 "B.CrtYd" user "Package Geometry/Place Bound Bottom")
		(35 "F.Fab" user "Ref Des/Assembly Top")
		(33 "B.Fab" user "Ref Des/Assembly Bottom")
	)
	(footprint ""
		(layer "B.Cu")
		(at 464.3755 -126.492 -90)
		(property "Reference" "C1M38"
			(at 0 0 90)
			(layer "B.SilkS")
			(hide yes)
			(effects
				(font
					(size 1.27 1.27)
				)
				(justify mirror)
			)
		)
		(property "Value" ""
			(at 0 0 90)
			(layer "B.Fab")
			(effects
				(font
					(size 1.27 1.27)
				)
				(justify mirror)
			)
		)
		(duplicate_pad_numbers_are_jumpers no)
		(fp_rect
			(start -0.3048 -0.1016)
			(end 0.3048 0.9906)
			(stroke
				(width 0)
				(type default)
			)
			(fill no)
			(layer "B.CrtYd")
		)
		(fp_line
			(start -0.3048 0.9906)
			(end -0.3048 -0.1016)
			(stroke
				(width 0.1)
				(type default)
			)
			(layer "B.Fab")
		)
		(fp_line
			(start 0.3048 0.9906)
			(end -0.3048 0.9906)
			(stroke
				(width 0.1)
				(type default)
			)
			(layer "B.Fab")
		)
		(fp_line
			(start -0.3048 -0.1016)
			(end 0.3048 -0.1016)
			(stroke
				(width 0.1)
				(type default)
			)
			(layer "B.Fab")
		)
		(fp_line
			(start 0.3048 -0.1016)
			(end 0.3048 0.9906)
			(stroke
				(width 0.1)
				(type default)
			)
			(layer "B.Fab")
		)
		(pad "1" smd rect
			(at 0 0 90)
			(size 0.508 0.508)
			(layers "B.Cu" "B.Mask" "B.Paste")
			(net "P5V_TPS2061")
		)
		(pad "2" smd rect
			(at 0 0.889 90)
			(size 0.508 0.508)
			(layers "B.Cu" "B.Mask" "B.Paste")
			(net "GND")
		)
		(zone
			(layer "B.Cu")
			(hatch none 0.5)
			(connect_pads
				(clearance 0)
			)
			(min_thickness 0.25)
			(keepout
				(tracks allowed)
				(vias not_allowed)
				(pads allowed)
				(copperpour not_allowed)
				(footprints allowed)
			)
			(placement
				(enabled no)
				(sheetname "")
			)
			(fill
				(thermal_gap 0.5)
				(thermal_bridge_width 0.5)
				(island_removal_mode 0)
			)
			(polygon
				(pts
					(xy 464.1215 -126.746) (xy 463.7405 -126.746) (xy 463.7405 -126.238) (xy 464.1215 -126.238)
				)
			)
		)
		(zone
			(layer "B.Cu")
			(hatch none 0.5)
			(connect_pads
				(clearance 0)
			)
			(min_thickness 0.25)
			(keepout
				(tracks not_allowed)
				(vias allowed)
				(pads allowed)
				(copperpour not_allowed)
				(footprints allowed)
			)
			(placement
				(enabled no)
				(sheetname "")
			)
			(fill
				(thermal_gap 0.5)
				(thermal_bridge_width 0.5)
				(island_removal_mode 0)
			)
			(polygon
				(pts
					(xy 464.1215 -126.746) (xy 463.7405 -126.746) (xy 463.7405 -126.238) (xy 464.1215 -126.238)
				)
			)
		)
	)
	(footprint ""
		(layer "B.Cu")
		(at 499.2878 -145.9738 180)
		(property "Reference" "R1L21"
			(at 0 0 0)
			(layer "B.SilkS")
			(hide yes)
			(effects
				(font
					(size 1.27 1.27)
				)
				(justify mirror)
			)
		)
		(property "Value" ""
			(at 0 0 0)
			(layer "B.Fab")
			(effects
				(font
					(size 1.27 1.27)
				)
				(justify mirror)
			)
		)
		(duplicate_pad_numbers_are_jumpers no)
		(fp_poly
			(pts
				(xy 0.2794 -0.1016) (xy -0.2794 -0.1016) (xy -0.2794 0.9906) (xy 0.2794 0.9906)
			)
			(stroke
				(width 0)
				(type default)
			)
			(fill no)
			(layer "B.CrtYd")
		)
		(fp_line
			(start 0.2794 0.9906)
			(end -0.2794 0.9906)
			(stroke
				(width 0.1)
				(type default)
			)
			(layer "B.Fab")
		)
		(fp_line
			(start 0.2794 -0.1016)
			(end 0.2794 0.9906)
			(stroke
				(width 0.1)
				(type default)
			)
			(layer "B.Fab")
		)
		(fp_line
			(start -0.2794 0.9906)
			(end -0.2794 -0.1016)
			(stroke
				(width 0.1)
				(type default)
			)
			(layer "B.Fab")
		)
		(fp_line
			(start -0.2794 -0.1016)
			(end 0.2794 -0.1016)
			(stroke
				(width 0.1)
				(type default)
			)
			(layer "B.Fab")
		)
		(pad "1" smd rect
			(at 0 0)
			(size 0.508 0.508)
			(layers "B.Cu" "B.Mask" "B.Paste")
			(net "P3V3")
		)
		(pad "2" smd rect
			(at 0 0.889)
			(size 0.508 0.508)
			(layers "B.Cu" "B.Mask" "B.Paste")
			(net "FP_LED_HDD_ACTIVITY_AND_R_N")
		)
		(zone
			(layer "B.Cu")
			(hatch none 0.5)
			(connect_pads
				(clearance 0)
			)
			(min_thickness 0.25)
			(keepout
				(tracks not_allowed)
				(vias allowed)
				(pads allowed)
				(copperpour not_allowed)
				(footprints allowed)
			)
			(placement
				(enabled no)
				(sheetname "")
			)
			(fill
				(thermal_gap 0.5)
				(thermal_bridge_width 0.5)
				(island_removal_mode 0)
			)
			(polygon
				(pts
					(xy 499.0338 -146.6088) (xy 499.5418 -146.6088) (xy 499.5418 -146.2278) (xy 499.0338 -146.2278)
				)
			)
		)
		(zone
			(layer "B.Cu")
			(hatch none 0.5)
			(connect_pads
				(clearance 0)
			)
			(min_thickness 0.25)
			(keepout
				(tracks allowed)
				(vias not_allowed)
				(pads allowed)
				(copperpour not_allowed)
				(footprints allowed)
			)
			(placement
				(enabled no)
				(sheetname "")
			)
			(fill
				(thermal_gap 0.5)
				(thermal_bridge_width 0.5)
				(island_removal_mode 0)
			)
			(polygon
				(pts
					(xy 499.0338 -146.2278) (xy 499.5418 -146.2278) (xy 499.5418 -146.6088) (xy 499.0338 -146.6088)
				)
			)
		)
	)
	(footprint ""
		(layer "B.Cu")
		(at 450.7484 -9.6012 -90)
		(property "Reference" "CR2U1"
			(at 1.93167 -1.016 0)
			(unlocked yes)
			(layer "B.SilkS")
			(effects
				(font
					(size 0.7874 0.5842)
					(thickness 0.1524)
				)
				(justify left mirror)
			)
		)
		(property "Value" ""
			(at 0 0 90)
			(layer "B.Fab")
			(effects
				(font
					(size 1.27 1.27)
				)
				(justify mirror)
			)
		)
		(duplicate_pad_numbers_are_jumpers no)
		(fp_line
			(start -1.8415 2.5273)
			(end -0.9652 2.5273)
			(stroke
				(width 0.1524)
				(type default)
			)
			(layer "B.SilkS")
		)
		(fp_line
			(start -1.8415 1.8542)
			(end -1.8415 2.5273)
			(stroke
				(width 0.1524)
				(type default)
			)
			(layer "B.SilkS")
		)
		(fp_line
			(start -1.8415 -0.4953)
			(end -1.8415 0.1778)
			(stroke
				(width 0.1524)
				(type default)
			)
			(layer "B.SilkS")
		)
		(fp_line
			(start -0.9652 -0.4953)
			(end -1.8415 -0.4953)
			(stroke
				(width 0.1524)
				(type default)
			)
			(layer "B.SilkS")
		)
		(fp_circle
			(center 0.988568 -1.098296)
			(end 0.988568 -1.225296)
			(stroke
				(width 0.254)
				(type default)
			)
			(fill no)
			(layer "B.SilkS")
		)
		(fp_poly
			(pts
				(xy -1.8415 2.5273) (xy -0.4445 2.5273) (xy -0.4445 -0.4953) (xy -1.8415 -0.4953)
			)
			(stroke
				(width 0)
				(type default)
			)
			(fill no)
			(layer "B.CrtYd")
		)
		(fp_rect
			(start -1.8415 2.5273)
			(end -0.4445 -0.4953)
			(stroke
				(width 0)
				(type default)
			)
			(fill no)
			(layer "B.Fab")
		)
		(fp_circle
			(center 0.988568 -1.098296)
			(end 0.988568 -1.225296)
			(stroke
				(width 0.254)
				(type default)
			)
			(fill no)
			(layer "B.Fab")
		)
		(pad "1" smd rect
			(at 0 0 90)
			(size 1.27 1.016)
			(layers "B.Cu" "B.Mask" "B.Paste")
			(net "P3V3_STBY")
		)
		(pad "2" smd rect
			(at 0 2.032 90)
			(size 1.27 1.016)
			(layers "B.Cu" "B.Mask" "B.Paste")
			(net "A_P3V_BAT_R")
		)
		(pad "3" smd rect
			(at -2.286 1.016 90)
			(size 1.27 1.016)
			(layers "B.Cu" "B.Mask" "B.Paste")
			(net "P3V3_RTC_STBY")
		)
	)
)
